(kicad_pcb
	(version 20260206)
	(generator "pcbnew")
	(generator_version "10.0")
	(general
		(thickness 1.6)
		(legacy_teardrops no)
	)
	(paper "A4")
	(title_block
		(title "timecard-production-celestica-r4006 — R4006-B0001-02_R01.brd")
		(comment 1 "Time Appliance Project (Time Card) / footprints 671-676 of 1113")
	)
	(layers
		(0 "F.Cu" signal "TOP")
		(4 "In1.Cu" signal "L02_GND1")
		(6 "In2.Cu" signal "L03_SIG1")
		(8 "In3.Cu" signal "L04_GND2")
		(10 "In4.Cu" signal "L05_VCC1")
		(12 "In5.Cu" signal "L06_VCC2")
		(14 "In6.Cu" signal "L07_GND3")
		(16 "In7.Cu" signal "L08_SIG2")
		(18 "In8.Cu" signal "L09_GND4")
		(2 "B.Cu" signal "BOTTOM")
		(9 "F.Adhes" user "F.Adhesive")
		(11 "B.Adhes" user "B.Adhesive")
		(13 "F.Paste" user "Package Geometry/Pastemask Top")
		(15 "B.Paste" user "Package Geometry/Pastemask Bottom")
		(5 "F.SilkS" user "Ref Des/Silkscreen Top")
		(7 "B.SilkS" user "Ref Des/Silkscreen Bottom")
		(1 "F.Mask" user "Board Geometry/Soldermask Top")
		(3 "B.Mask" user "Board Geometry/Soldermask Bottom")
		(17 "Dwgs.User" user "User.Drawings")
		(19 "Cmts.User" user "User.Comments")
		(21 "Eco1.User" user "User.Eco1")
		(23 "Eco2.User" user "User.Eco2")
		(25 "Edge.Cuts" user "Board Geometry/Outline")
		(27 "Margin" user)
		(31 "F.CrtYd" user "Package Geometry/Place Bound Top")
		(29 "B.CrtYd" user "Package Geometry/Place Bound Bottom")
		(35 "F.Fab" user "Ref Des/Assembly Top")
		(33 "B.Fab" user "Ref Des/Assembly Bottom")
	)
	(footprint ""
		(layer "F.Cu")
		(at 94.107 -21.336)
		(property "Reference" "TP50"
			(at -2.3622 1.43637 0)
			(unlocked yes)
			(layer "F.SilkS")
			(effects
				(font
					(size 0.7874 0.5842)
					(thickness 0.1524)
				)
				(justify left)
			)
		)
		(property "Value" ""
			(at 0 0 0)
			(layer "F.Fab")
			(effects
				(font
					(size 1.27 1.27)
				)
			)
		)
		(property "Device Type" "TP_PIONT-TP010CT020B030_PTH-TPA"
			(at -1.341882 0.996696 0)
			(unlocked yes)
			(layer "F.Fab")
			(hide yes)
			(effects
				(font
					(size 0.7874 0.5842)
					(thickness 0.000001)
				)
				(justify left)
			)
		)
		(duplicate_pad_numbers_are_jumpers no)
		(fp_poly
			(pts
				(arc
					(start 0.889 0)
					(mid -0.889 0)
					(end 0.889 0)
				)
			)
			(stroke
				(width 0)
				(type default)
			)
			(fill no)
			(layer "B.CrtYd")
		)
		(fp_poly
			(pts
				(arc
					(start 0.889 0)
					(mid -0.889 0)
					(end 0.889 0)
				)
			)
			(stroke
				(width 0)
				(type default)
			)
			(fill no)
			(layer "F.CrtYd")
		)
		(pad "1" thru_hole circle
			(at 0 0)
			(size 0.508 0.508)
			(drill 0.254)
			(layers "*.Cu" "*.Mask")
			(remove_unused_layers no)
			(net "CLK_125M_OE")
			(clearance 0.1016)
			(padstack
				(mode front_inner_back)
				(layer "Inner"
					(shape circle)
					(size 0.508 0.508)
					(clearance 0.1016)
				)
				(layer "B.Cu"
					(shape circle)
					(size 0.762 0.762)
					(clearance -0.0254)
				)
			)
		)
	)
	(footprint ""
		(layer "F.Cu")
		(at 146.6088 -17.2466 -90)
		(property "Reference" "C227"
			(at 1.79197 -2.6162 0)
			(unlocked yes)
			(layer "F.SilkS")
			(effects
				(font
					(size 0.7874 0.5842)
					(thickness 0.1524)
				)
			)
		)
		(property "Value" "VAL*"
			(at 0.0762 2.067306 270)
			(unlocked yes)
			(layer "F.Fab")
			(hide yes)
			(effects
				(font
					(size 0.7874 0.5842)
					(thickness 0.1524)
				)
			)
		)
		(property "Tolerance" "TOL*"
			(at 0.0762 3.032506 270)
			(unlocked yes)
			(layer "Cmts.User")
			(hide yes)
			(effects
				(font
					(size 0.7874 0.5842)
					(thickness 0.1524)
				)
			)
		)
		(property "User Part Number" "PARTNUM*"
			(at 0.1016 4.023106 270)
			(unlocked yes)
			(layer "Cmts.User")
			(hide yes)
			(effects
				(font
					(size 0.7874 0.5842)
					(thickness 0.1524)
				)
			)
		)
		(property "Device Type" "CAPACITOR-G105-0B104-EK,0.1UF,A"
			(at 0.0508 1.127506 270)
			(unlocked yes)
			(layer "F.Fab")
			(hide yes)
			(effects
				(font
					(size 0.7874 0.5842)
					(thickness 0.1524)
				)
			)
		)
		(duplicate_pad_numbers_are_jumpers no)
		(fp_line
			(start -1.143 0.5588)
			(end 1.143 0.5588)
			(stroke
				(width 0.1)
				(type default)
			)
			(layer "F.SilkS")
		)
		(fp_line
			(start 1.143 0.5588)
			(end 1.143 -0.5588)
			(stroke
				(width 0.1)
				(type default)
			)
			(layer "F.SilkS")
		)
		(fp_line
			(start -1.143 -0.5588)
			(end -1.143 0.5588)
			(stroke
				(width 0.1)
				(type default)
			)
			(layer "F.SilkS")
		)
		(fp_line
			(start 1.143 -0.5588)
			(end -1.143 -0.5588)
			(stroke
				(width 0.1)
				(type default)
			)
			(layer "F.SilkS")
		)
		(fp_rect
			(start -1.143 -0.5588)
			(end 1.143 0.5588)
			(stroke
				(width 0)
				(type default)
			)
			(fill no)
			(layer "F.CrtYd")
		)
		(fp_line
			(start -0.508 0.3048)
			(end 0.508 0.3048)
			(stroke
				(width 0.1)
				(type default)
			)
			(layer "F.Fab")
		)
		(fp_line
			(start 0.508 0.3048)
			(end 0.508 -0.3048)
			(stroke
				(width 0.1)
				(type default)
			)
			(layer "F.Fab")
		)
		(fp_line
			(start -0.508 -0.3048)
			(end -0.508 0.3048)
			(stroke
				(width 0.1)
				(type default)
			)
			(layer "F.Fab")
		)
		(fp_line
			(start 0.508 -0.3048)
			(end -0.508 -0.3048)
			(stroke
				(width 0.1)
				(type default)
			)
			(layer "F.Fab")
		)
		(pad "1" smd rect
			(at -0.5334 0 270)
			(size 0.7112 0.6096)
			(layers "F.Cu" "F.Mask" "F.Paste")
			(net "UNNAMED_515_CAPACITOR_I128_1")
		)
		(pad "2" smd rect
			(at 0.5334 0 270)
			(size 0.7112 0.6096)
			(layers "F.Cu" "F.Mask" "F.Paste")
			(net "SG")
		)
		(zone
			(layer "F.Cu")
			(hatch none 0.5)
			(connect_pads
				(clearance 0)
			)
			(min_thickness 0.25)
			(keepout
				(tracks allowed)
				(vias not_allowed)
				(pads allowed)
				(copperpour not_allowed)
				(footprints allowed)
			)
			(placement
				(enabled no)
				(sheetname "")
			)
			(fill
				(thermal_gap 0.5)
				(thermal_bridge_width 0.5)
				(island_removal_mode 0)
			)
			(polygon
				(pts
					(xy 146.9136 -17.3228) (xy 146.304 -17.3228) (xy 146.304 -17.1704) (xy 146.9136 -17.1704)
				)
			)
		)
	)
	(footprint ""
		(layer "B.Cu")
		(at 139.065 -72.898 180)
		(property "Reference" "R43"
			(at 2.286 0.21463 0)
			(unlocked yes)
			(layer "B.SilkS")
			(effects
				(font
					(size 0.7874 0.5842)
					(thickness 0.1524)
				)
				(justify mirror)
			)
		)
		(property "Value" "VAL*"
			(at -0.02032 2.13233 180)
			(unlocked yes)
			(layer "B.Fab")
			(hide yes)
			(effects
				(font
					(size 0.7874 0.5842)
					(thickness 0.1524)
				)
				(justify mirror)
			)
		)
		(property "Tolerance" "TOL*"
			(at -0.044704 3.05435 180)
			(unlocked yes)
			(layer "Cmts.User")
			(hide yes)
			(effects
				(font
					(size 0.7874 0.5842)
					(thickness 0.1524)
				)
				(justify mirror)
			)
		)
		(property "User Part Number" "PARTNUM*"
			(at -0.02032 4.024884 180)
			(unlocked yes)
			(layer "Cmts.User")
			(hide yes)
			(effects
				(font
					(size 0.7874 0.5842)
					(thickness 0.1524)
				)
				(justify mirror)
			)
		)
		(property "Device Type" "RESISTOR-G155-100R0-J0,0OHM,-"
			(at -0.008382 1.210564 180)
			(unlocked yes)
			(layer "B.Fab")
			(hide yes)
			(effects
				(font
					(size 0.7874 0.5842)
					(thickness 0.1524)
				)
				(justify mirror)
			)
		)
		(duplicate_pad_numbers_are_jumpers no)
		(fp_line
			(start 1.143 0.5588)
			(end -1.143 0.5588)
			(stroke
				(width 0.1)
				(type default)
			)
			(layer "B.SilkS")
		)
		(fp_line
			(start 1.143 -0.5588)
			(end 1.143 0.5588)
			(stroke
				(width 0.1)
				(type default)
			)
			(layer "B.SilkS")
		)
		(fp_line
			(start -1.143 0.5588)
			(end -1.143 -0.5588)
			(stroke
				(width 0.1)
				(type default)
			)
			(layer "B.SilkS")
		)
		(fp_line
			(start -1.143 -0.5588)
			(end 1.143 -0.5588)
			(stroke
				(width 0.1)
				(type default)
			)
			(layer "B.SilkS")
		)
		(fp_rect
			(start 1.143 0.5588)
			(end -1.143 -0.5588)
			(stroke
				(width 0)
				(type default)
			)
			(fill no)
			(layer "B.CrtYd")
		)
		(fp_line
			(start 0.508 0.3048)
			(end -0.508 0.3048)
			(stroke
				(width 0.1)
				(type default)
			)
			(layer "B.Fab")
		)
		(fp_line
			(start 0.508 -0.3048)
			(end 0.508 0.3048)
			(stroke
				(width 0.1)
				(type default)
			)
			(layer "B.Fab")
		)
		(fp_line
			(start -0.508 0.3048)
			(end -0.508 -0.3048)
			(stroke
				(width 0.1)
				(type default)
			)
			(layer "B.Fab")
		)
		(fp_line
			(start -0.508 -0.3048)
			(end 0.508 -0.3048)
			(stroke
				(width 0.1)
				(type default)
			)
			(layer "B.Fab")
		)
		(pad "1" smd rect
			(at 0.5334 0)
			(size 0.7112 0.6096)
			(layers "B.Cu" "B.Mask" "B.Paste")
			(net "PCIE_CONN_TMS")
		)
		(pad "2" smd rect
			(at -0.5334 0)
			(size 0.7112 0.6096)
			(layers "B.Cu" "B.Mask" "B.Paste")
			(net "FPGA_TMS")
		)
		(zone
			(layer "B.Cu")
			(hatch none 0.5)
			(connect_pads
				(clearance 0)
			)
			(min_thickness 0.25)
			(keepout
				(tracks allowed)
				(vias not_allowed)
				(pads allowed)
				(copperpour not_allowed)
				(footprints allowed)
			)
			(placement
				(enabled no)
				(sheetname "")
			)
			(fill
				(thermal_gap 0.5)
				(thermal_bridge_width 0.5)
				(island_removal_mode 0)
			)
			(polygon
				(pts
					(xy 138.9888 -73.2028) (xy 138.9888 -72.5932) (xy 139.1412 -72.5932) (xy 139.1412 -73.2028)
				)
			)
		)
	)
	(footprint ""
		(layer "B.Cu")
		(at 140.335 -67.056)
		(property "Reference" "R134"
			(at 1.73863 -1.143 270)
			(unlocked yes)
			(layer "B.SilkS")
			(effects
				(font
					(size 0.7874 0.5842)
					(thickness 0.1524)
				)
				(justify mirror)
			)
		)
		(property "Value" "VAL*"
			(at -0.02032 2.13233 0)
			(unlocked yes)
			(layer "B.Fab")
			(hide yes)
			(effects
				(font
					(size 0.7874 0.5842)
					(thickness 0.1524)
				)
				(justify mirror)
			)
		)
		(property "Tolerance" "TOL*"
			(at -0.044704 3.05435 0)
			(unlocked yes)
			(layer "Cmts.User")
			(hide yes)
			(effects
				(font
					(size 0.7874 0.5842)
					(thickness 0.1524)
				)
				(justify mirror)
			)
		)
		(property "User Part Number" "PARTNUM*"
			(at -0.02032 4.024884 0)
			(unlocked yes)
			(layer "Cmts.User")
			(hide yes)
			(effects
				(font
					(size 0.7874 0.5842)
					(thickness 0.1524)
				)
				(justify mirror)
			)
		)
		(property "Device Type" "RESISTOR-G155-133R0-01,33OHM,1%"
			(at -0.008382 1.210564 0)
			(unlocked yes)
			(layer "B.Fab")
			(hide yes)
			(effects
				(font
					(size 0.7874 0.5842)
					(thickness 0.1524)
				)
				(justify mirror)
			)
		)
		(duplicate_pad_numbers_are_jumpers no)
		(fp_line
			(start -1.143 -0.5588)
			(end 1.143 -0.5588)
			(stroke
				(width 0.1)
				(type default)
			)
			(layer "B.SilkS")
		)
		(fp_line
			(start -1.143 0.5588)
			(end -1.143 -0.5588)
			(stroke
				(width 0.1)
				(type default)
			)
			(layer "B.SilkS")
		)
		(fp_line
			(start 1.143 -0.5588)
			(end 1.143 0.5588)
			(stroke
				(width 0.1)
				(type default)
			)
			(layer "B.SilkS")
		)
		(fp_line
			(start 1.143 0.5588)
			(end -1.143 0.5588)
			(stroke
				(width 0.1)
				(type default)
			)
			(layer "B.SilkS")
		)
		(fp_rect
			(start -1.143 -0.5588)
			(end 1.143 0.5588)
			(stroke
				(width 0)
				(type default)
			)
			(fill no)
			(layer "B.CrtYd")
		)
		(fp_line
			(start -0.508 -0.3048)
			(end 0.508 -0.3048)
			(stroke
				(width 0.1)
				(type default)
			)
			(layer "B.Fab")
		)
		(fp_line
			(start -0.508 0.3048)
			(end -0.508 -0.3048)
			(stroke
				(width 0.1)
				(type default)
			)
			(layer "B.Fab")
		)
		(fp_line
			(start 0.508 -0.3048)
			(end 0.508 0.3048)
			(stroke
				(width 0.1)
				(type default)
			)
			(layer "B.Fab")
		)
		(fp_line
			(start 0.508 0.3048)
			(end -0.508 0.3048)
			(stroke
				(width 0.1)
				(type default)
			)
			(layer "B.Fab")
		)
		(pad "1" smd rect
			(at 0.5334 0 180)
			(size 0.7112 0.6096)
			(layers "B.Cu" "B.Mask" "B.Paste")
			(net "FT4232_FPGA_TCK")
		)
		(pad "2" smd rect
			(at -0.5334 0 180)
			(size 0.7112 0.6096)
			(layers "B.Cu" "B.Mask" "B.Paste")
			(net "FPGA_TCK")
		)
		(zone
			(layer "B.Cu")
			(hatch none 0.5)
			(connect_pads
				(clearance 0)
			)
			(min_thickness 0.25)
			(keepout
				(tracks allowed)
				(vias not_allowed)
				(pads allowed)
				(copperpour not_allowed)
				(footprints allowed)
			)
			(placement
				(enabled no)
				(sheetname "")
			)
			(fill
				(thermal_gap 0.5)
				(thermal_bridge_width 0.5)
				(island_removal_mode 0)
			)
			(polygon
				(pts
					(xy 140.2588 -67.3608) (xy 140.2588 -66.7512) (xy 140.4112 -66.7512) (xy 140.4112 -67.3608)
				)
			)
		)
	)
	(footprint ""
		(layer "B.Cu")
		(at 162.56 -27.432 180)
		(property "Reference" "R417"
			(at 0.508 2.11963 0)
			(unlocked yes)
			(layer "B.SilkS")
			(effects
				(font
					(size 0.7874 0.5842)
					(thickness 0.1524)
				)
				(justify mirror)
			)
		)
		(property "Value" "VAL*"
			(at -0.02032 2.13233 180)
			(unlocked yes)
			(layer "B.Fab")
			(hide yes)
			(effects
				(font
					(size 0.7874 0.5842)
					(thickness 0.1524)
				)
				(justify mirror)
			)
		)
		(property "Tolerance" "TOL*"
			(at -0.044704 3.05435 180)
			(unlocked yes)
			(layer "Cmts.User")
			(hide yes)
			(effects
				(font
					(size 0.7874 0.5842)
					(thickness 0.1524)
				)
				(justify mirror)
			)
		)
		(property "User Part Number" "PARTNUM*"
			(at -0.02032 4.024884 180)
			(unlocked yes)
			(layer "Cmts.User")
			(hide yes)
			(effects
				(font
					(size 0.7874 0.5842)
					(thickness 0.1524)
				)
				(justify mirror)
			)
		)
		(property "Device Type" "RESISTOR-G155-11001-01,1KOHM,1%"
			(at -0.008382 1.210564 180)
			(unlocked yes)
			(layer "B.Fab")
			(hide yes)
			(effects
				(font
					(size 0.7874 0.5842)
					(thickness 0.1524)
				)
				(justify mirror)
			)
		)
		(duplicate_pad_numbers_are_jumpers no)
		(fp_line
			(start 1.143 0.5588)
			(end -1.143 0.5588)
			(stroke
				(width 0.1)
				(type default)
			)
			(layer "B.SilkS")
		)
		(fp_line
			(start 1.143 -0.5588)
			(end 1.143 0.5588)
			(stroke
				(width 0.1)
				(type default)
			)
			(layer "B.SilkS")
		)
		(fp_line
			(start -1.143 0.5588)
			(end -1.143 -0.5588)
			(stroke
				(width 0.1)
				(type default)
			)
			(layer "B.SilkS")
		)
		(fp_line
			(start -1.143 -0.5588)
			(end 1.143 -0.5588)
			(stroke
				(width 0.1)
				(type default)
			)
			(layer "B.SilkS")
		)
		(fp_rect
			(start 1.143 -0.5588)
			(end -1.143 0.5588)
			(stroke
				(width 0)
				(type default)
			)
			(fill no)
			(layer "B.CrtYd")
		)
		(fp_line
			(start 0.508 0.3048)
			(end -0.508 0.3048)
			(stroke
				(width 0.1)
				(type default)
			)
			(layer "B.Fab")
		)
		(fp_line
			(start 0.508 -0.3048)
			(end 0.508 0.3048)
			(stroke
				(width 0.1)
				(type default)
			)
			(layer "B.Fab")
		)
		(fp_line
			(start -0.508 0.3048)
			(end -0.508 -0.3048)
			(stroke
				(width 0.1)
				(type default)
			)
			(layer "B.Fab")
		)
		(fp_line
			(start -0.508 -0.3048)
			(end 0.508 -0.3048)
			(stroke
				(width 0.1)
				(type default)
			)
			(layer "B.Fab")
		)
		(pad "1" smd rect
			(at 0.5334 0)
			(size 0.7112 0.6096)
			(layers "B.Cu" "B.Mask" "B.Paste")
			(net "UNNAMED_6_LM75BDPTSSOP8_I81_A0")
		)
		(pad "2" smd rect
			(at -0.5334 0)
			(size 0.7112 0.6096)
			(layers "B.Cu" "B.Mask" "B.Paste")
			(net "SG")
		)
		(zone
			(layer "B.Cu")
			(hatch none 0.5)
			(connect_pads
				(clearance 0)
			)
			(min_thickness 0.25)
			(keepout
				(tracks not_allowed)
				(vias allowed)
				(pads allowed)
				(copperpour not_allowed)
				(footprints allowed)
			)
			(placement
				(enabled no)
				(sheetname "")
			)
			(fill
				(thermal_gap 0.5)
				(thermal_bridge_width 0.5)
				(island_removal_mode 0)
			)
			(polygon
				(pts
					(xy 162.4838 -27.1272) (xy 162.6362 -27.1272) (xy 162.6362 -27.7368) (xy 162.4838 -27.7368)
				)
			)
		)
		(zone
			(layer "B.Cu")
			(hatch none 0.5)
			(connect_pads
				(clearance 0)
			)
			(min_thickness 0.25)
			(keepout
				(tracks allowed)
				(vias not_allowed)
				(pads allowed)
				(copperpour not_allowed)
				(footprints allowed)
			)
			(placement
				(enabled no)
				(sheetname "")
			)
			(fill
				(thermal_gap 0.5)
				(thermal_bridge_width 0.5)
				(island_removal_mode 0)
			)
			(polygon
				(pts
					(xy 162.4838 -27.1272) (xy 162.6362 -27.1272) (xy 162.6362 -27.7368) (xy 162.4838 -27.7368)
				)
			)
		)
	)
	(footprint ""
		(layer "B.Cu")
		(at 105.8418 -72.517)
		(property "Reference" "C243"
			(at -3.81 -0.08763 0)
			(unlocked yes)
			(layer "B.SilkS")
			(effects
				(font
					(size 0.7874 0.5842)
					(thickness 0.1524)
				)
				(justify mirror)
			)
		)
		(property "Value" "VAL*"
			(at -0.0762 3.134106 0)
			(unlocked yes)
			(layer "B.Fab")
			(hide yes)
			(effects
				(font
					(size 0.7874 0.5842)
					(thickness 0.1524)
				)
				(justify mirror)
			)
		)
		(property "Device Type" "CAPACITOR-G107-0F226-CM,22UF,2A"
			(at -0.0508 2.194306 0)
			(unlocked yes)
			(layer "B.Fab")
			(hide yes)
			(effects
				(font
					(size 0.7874 0.5842)
					(thickness 0.1524)
				)
				(justify mirror)
			)
		)
		(property "User Part Number" "PARTNUM*"
			(at -0.1016 5.013706 0)
			(unlocked yes)
			(layer "Cmts.User")
			(hide yes)
			(effects
				(font
					(size 0.7874 0.5842)
					(thickness 0.1524)
				)
				(justify mirror)
			)
		)
		(property "Tolerance" "TOL*"
			(at -0.0762 4.048506 0)
			(unlocked yes)
			(layer "Cmts.User")
			(hide yes)
			(effects
				(font
					(size 0.7874 0.5842)
					(thickness 0.1524)
				)
				(justify mirror)
			)
		)
		(duplicate_pad_numbers_are_jumpers no)
		(fp_line
			(start -1.5748 -0.9398)
			(end 1.5748 -0.9398)
			(stroke
				(width 0.1)
				(type default)
			)
			(layer "B.SilkS")
		)
		(fp_line
			(start -1.5748 0.9398)
			(end -1.5748 -0.9398)
			(stroke
				(width 0.1)
				(type default)
			)
			(layer "B.SilkS")
		)
		(fp_line
			(start 1.5748 -0.9398)
			(end 1.5748 0.9398)
			(stroke
				(width 0.1)
				(type default)
			)
			(layer "B.SilkS")
		)
		(fp_line
			(start 1.5748 0.9398)
			(end -1.5748 0.9398)
			(stroke
				(width 0.1)
				(type default)
			)
			(layer "B.SilkS")
		)
		(fp_rect
			(start 1.5748 -0.9398)
			(end -1.5748 0.9398)
			(stroke
				(width 0)
				(type default)
			)
			(fill no)
			(layer "B.CrtYd")
		)
		(fp_line
			(start -1.016 -0.635)
			(end 1.016 -0.635)
			(stroke
				(width 0.1)
				(type default)
			)
			(layer "B.Fab")
		)
		(fp_line
			(start -1.016 0.635)
			(end -1.016 -0.635)
			(stroke
				(width 0.1)
				(type default)
			)
			(layer "B.Fab")
		)
		(fp_line
			(start 1.016 -0.635)
			(end 1.016 0.635)
			(stroke
				(width 0.1)
				(type default)
			)
			(layer "B.Fab")
		)
		(fp_line
			(start 1.016 0.635)
			(end -1.016 0.635)
			(stroke
				(width 0.1)
				(type default)
			)
			(layer "B.Fab")
		)
		(pad "1" smd rect
			(at 0.8382 0 180)
			(size 0.9652 1.3716)
			(layers "B.Cu" "B.Mask" "B.Paste")
			(net "XP3R3V_FPGA")
		)
		(pad "2" smd rect
			(at -0.8382 0 180)
			(size 0.9652 1.3716)
			(layers "B.Cu" "B.Mask" "B.Paste")
			(net "SG")
		)
		(zone
			(layer "B.Cu")
			(hatch none 0.5)
			(connect_pads
				(clearance 0)
			)
			(min_thickness 0.25)
			(keepout
				(tracks allowed)
				(vias not_allowed)
				(pads allowed)
				(copperpour not_allowed)
				(footprints allowed)
			)
			(placement
				(enabled no)
				(sheetname "")
			)
			(fill
				(thermal_gap 0.5)
				(thermal_bridge_width 0.5)
				(island_removal_mode 0)
			)
			(polygon
				(pts
					(xy 106.0704 -73.152) (xy 105.6132 -73.152) (xy 105.6132 -71.882) (xy 106.0704 -71.882)
				)
			)
		)
	)
)
